# S9S_MB_2U (Grand Teton) — schematic netlist excerpt (pin names and nets, part order shuffled) for the footprints in the layout excerpt that follows; sources: Cadence DE-HDL packaged netlist, KiCad conversion of 03242023_DA0F0TMBIJ0_F0T_Motherboard_J_brd_V01_OCP.brd

PR297  Q_RES  8.87K 1% EMPTY  pkg 0402LF  page 286 : A = PVCCIN_CPU1_LSET4 ; B = GND
PC223  Q_CAP  100NF 50V 10% EMPTY  pkg C0402  page 274 : A = PVCCINFAON_CPU0_VCC ; B = GND

(kicad_pcb
	(version 20260206)
	(generator "pcbnew")
	(generator_version "10.0")
	(general
		(thickness 1.6)
		(legacy_teardrops no)
	)
	(paper "A4")
	(title_block
		(title "03242023_DA0F0TMBIJ0_F0T_Motherboard_J_brd_V01_OCP.brd")
		(comment 1 "Grand Teton / footprints 568-569 of 6105")
	)
	(layers
		(0 "F.Cu" signal "TOP")
		(4 "In1.Cu" signal "GND")
		(6 "In2.Cu" signal "IN1")
		(8 "In3.Cu" signal "GND1")
		(10 "In4.Cu" signal "IN2")
		(12 "In5.Cu" signal "GND2")
		(14 "In6.Cu" signal "IN3")
		(16 "In7.Cu" signal "GND3")
		(18 "In8.Cu" signal "VCC")
		(20 "In9.Cu" signal "VCC1")
		(22 "In10.Cu" signal "GND4")
		(24 "In11.Cu" signal "IN4")
		(26 "In12.Cu" signal "GND5")
		(28 "In13.Cu" signal "IN5")
		(30 "In14.Cu" signal "GND6")
		(32 "In15.Cu" signal "IN6")
		(34 "In16.Cu" signal "GND7")
		(2 "B.Cu" signal "BOTTOM")
		(9 "F.Adhes" user "F.Adhesive")
		(11 "B.Adhes" user "B.Adhesive")
		(13 "F.Paste" user "Package Geometry/Pastemask Top")
		(15 "B.Paste" user "Package Geometry/Pastemask Bottom")
		(5 "F.SilkS" user "Ref Des/Silkscreen Top")
		(7 "B.SilkS" user "Ref Des/Silkscreen Bottom")
		(1 "F.Mask" user "Board Geometry/Soldermask Top")
		(3 "B.Mask" user "Board Geometry/Soldermask Bottom")
		(17 "Dwgs.User" user "User.Drawings")
		(19 "Cmts.User" user "User.Comments")
		(21 "Eco1.User" user "User.Eco1")
		(23 "Eco2.User" user "User.Eco2")
		(25 "Edge.Cuts" user "Board Geometry/Outline")
		(27 "Margin" user)
		(31 "F.CrtYd" user "Package Geometry/Place Bound Top")
		(29 "B.CrtYd" user "Package Geometry/Place Bound Bottom")
		(35 "F.Fab" user "Ref Des/Assembly Top")
		(33 "B.Fab" user "Ref Des/Assembly Bottom")
	)
	(footprint ""
		(layer "F.Cu")
		(at 420.682166 -133.114034 180)
		(property "Reference" "PC223"
			(at 0 0 180)
			(layer "F.SilkS")
			(hide yes)
			(effects
				(font
					(size 1.27 1.27)
				)
			)
		)
		(property "Value" ""
			(at 0 0 180)
			(layer "F.Fab")
			(effects
				(font
					(size 1.27 1.27)
				)
			)
		)
		(duplicate_pad_numbers_are_jumpers no)
		(fp_line
			(start 0.7874 0.4064)
			(end -0.7874 0.4064)
			(stroke
				(width 0.1524)
				(type default)
			)
			(layer "F.SilkS")
		)
		(fp_line
			(start 0.7874 -0.4064)
			(end 0.7874 0.4064)
			(stroke
				(width 0.1524)
				(type default)
			)
			(layer "F.SilkS")
		)
		(fp_line
			(start -0.7874 0.4064)
			(end -0.7874 -0.4064)
			(stroke
				(width 0.1524)
				(type default)
			)
			(layer "F.SilkS")
		)
		(fp_line
			(start -0.7874 -0.4064)
			(end 0.7874 -0.4064)
			(stroke
				(width 0.1524)
				(type default)
			)
			(layer "F.SilkS")
		)
		(fp_line
			(start 0.67945 0.3048)
			(end 0.120396 0.3048)
			(stroke
				(width 0.1)
				(type default)
			)
			(layer "F.Fab")
		)
		(fp_line
			(start 0.67945 -0.3048)
			(end 0.67945 0.3048)
			(stroke
				(width 0.1)
				(type default)
			)
			(layer "F.Fab")
		)
		(fp_line
			(start 0.12065 -0.2794)
			(end 0.12065 -0.3048)
			(stroke
				(width 0.1)
				(type default)
			)
			(layer "F.Fab")
		)
		(fp_line
			(start 0.12065 -0.3048)
			(end 0.67945 -0.3048)
			(stroke
				(width 0.1)
				(type default)
			)
			(layer "F.Fab")
		)
		(fp_line
			(start 0.120396 0.3048)
			(end 0.120396 0.2794)
			(stroke
				(width 0.1)
				(type default)
			)
			(layer "F.Fab")
		)
		(fp_line
			(start 0.120396 0.2794)
			(end -0.12065 0.2794)
			(stroke
				(width 0.1)
				(type default)
			)
			(layer "F.Fab")
		)
		(fp_line
			(start -0.12065 0.3048)
			(end -0.67945 0.3048)
			(stroke
				(width 0.1)
				(type default)
			)
			(layer "F.Fab")
		)
		(fp_line
			(start -0.12065 0.2794)
			(end -0.12065 0.3048)
			(stroke
				(width 0.1)
				(type default)
			)
			(layer "F.Fab")
		)
		(fp_line
			(start -0.12065 -0.2794)
			(end 0.12065 -0.2794)
			(stroke
				(width 0.1)
				(type default)
			)
			(layer "F.Fab")
		)
		(fp_line
			(start -0.12065 -0.305054)
			(end -0.12065 -0.2794)
			(stroke
				(width 0.1)
				(type default)
			)
			(layer "F.Fab")
		)
		(fp_line
			(start -0.67945 0.3048)
			(end -0.67945 -0.305054)
			(stroke
				(width 0.1)
				(type default)
			)
			(layer "F.Fab")
		)
		(fp_line
			(start -0.67945 -0.305054)
			(end -0.12065 -0.305054)
			(stroke
				(width 0.1)
				(type default)
			)
			(layer "F.Fab")
		)
		(pad "1" smd circle
			(at -0.40005 0 180)
			(size 0 0)
			(layers "F.Cu" "F.Mask" "F.Paste")
			(net "PVCCINFAON_CPU0_VCC")
		)
		(pad "2" smd circle
			(at 0.40005 0 180)
			(size 0 0)
			(layers "F.Cu" "F.Mask" "F.Paste")
			(net "GND")
		)
	)
	(footprint ""
		(layer "F.Cu")
		(at 120.187974 -338.86013)
		(property "Reference" "PR297"
			(at 0 0 0)
			(layer "F.SilkS")
			(hide yes)
			(effects
				(font
					(size 1.27 1.27)
				)
			)
		)
		(property "Value" ""
			(at 0 0 0)
			(layer "F.Fab")
			(effects
				(font
					(size 1.27 1.27)
				)
			)
		)
		(duplicate_pad_numbers_are_jumpers no)
		(fp_line
			(start -0.7874 -0.4064)
			(end 0.7874 -0.4064)
			(stroke
				(width 0.1524)
				(type default)
			)
			(layer "F.SilkS")
		)
		(fp_line
			(start -0.7874 0.4064)
			(end -0.7874 -0.4064)
			(stroke
				(width 0.1524)
				(type default)
			)
			(layer "F.SilkS")
		)
		(fp_line
			(start 0.7874 -0.4064)
			(end 0.7874 0.4064)
			(stroke
				(width 0.1524)
				(type default)
			)
			(layer "F.SilkS")
		)
		(fp_line
			(start 0.7874 0.4064)
			(end -0.7874 0.4064)
			(stroke
				(width 0.1524)
				(type default)
			)
			(layer "F.SilkS")
		)
		(fp_line
			(start -0.67945 -0.305054)
			(end -0.12065 -0.305054)
			(stroke
				(width 0.1)
				(type default)
			)
			(layer "F.Fab")
		)
		(fp_line
			(start -0.67945 0.3048)
			(end -0.67945 -0.305054)
			(stroke
				(width 0.1)
				(type default)
			)
			(layer "F.Fab")
		)
		(fp_line
			(start -0.12065 -0.305054)
			(end -0.12065 -0.2794)
			(stroke
				(width 0.1)
				(type default)
			)
			(layer "F.Fab")
		)
		(fp_line
			(start -0.12065 -0.2794)
			(end 0.12065 -0.2794)
			(stroke
				(width 0.1)
				(type default)
			)
			(layer "F.Fab")
		)
		(fp_line
			(start -0.12065 0.2794)
			(end -0.12065 0.3048)
			(stroke
				(width 0.1)
				(type default)
			)
			(layer "F.Fab")
		)
		(fp_line
			(start -0.12065 0.3048)
			(end -0.67945 0.3048)
			(stroke
				(width 0.1)
				(type default)
			)
			(layer "F.Fab")
		)
		(fp_line
			(start 0.120396 0.2794)
			(end -0.12065 0.2794)
			(stroke
				(width 0.1)
				(type default)
			)
			(layer "F.Fab")
		)
		(fp_line
			(start 0.120396 0.3048)
			(end 0.120396 0.2794)
			(stroke
				(width 0.1)
				(type default)
			)
			(layer "F.Fab")
		)
		(fp_line
			(start 0.12065 -0.3048)
			(end 0.67945 -0.3048)
			(stroke
				(width 0.1)
				(type default)
			)
			(layer "F.Fab")
		)
		(fp_line
			(start 0.12065 -0.2794)
			(end 0.12065 -0.3048)
			(stroke
				(width 0.1)
				(type default)
			)
			(layer "F.Fab")
		)
		(fp_line
			(start 0.67945 -0.3048)
			(end 0.67945 0.3048)
			(stroke
				(width 0.1)
				(type default)
			)
			(layer "F.Fab")
		)
		(fp_line
			(start 0.67945 0.3048)
			(end 0.120396 0.3048)
			(stroke
				(width 0.1)
				(type default)
			)
			(layer "F.Fab")
		)
		(pad "1" smd circle
			(at -0.40005 0)
			(size 0 0)
			(layers "F.Cu" "F.Mask" "F.Paste")
			(net "PVCCIN_CPU1_LSET4")
		)
		(pad "2" smd circle
			(at 0.40005 0)
			(size 0 0)
			(layers "F.Cu" "F.Mask" "F.Paste")
			(net "GND")
		)
	)
)
